(kicad_pcb
	(version 20241229)
	(generator "pcbnew")
	(generator_version "9.0")
	(general
		(thickness 1.62)
		(legacy_teardrops no)
	)
	(paper "A3")
	(title_block
		(title "COM Express 7 Baseboard")
		(date "2025-02-04")
		(rev "1.1.2")
		(company "Antmicro Ltd")
		(comment 1 "www.antmicro.com")
		(comment 9 "footprint 27 of 802 (U37), pads 42-50 of 50")
	)
	(layers
		(0 "F.Cu" signal)
		(4 "In1.Cu" signal)
		(6 "In2.Cu" signal)
		(8 "In3.Cu" signal)
		(10 "In4.Cu" signal)
		(12 "In5.Cu" signal)
		(14 "In6.Cu" signal)
		(2 "B.Cu" signal)
		(9 "F.Adhes" user "F.Adhesive")
		(11 "B.Adhes" user "B.Adhesive")
		(13 "F.Paste" user)
		(15 "B.Paste" user)
		(5 "F.SilkS" user "F.Silkscreen")
		(7 "B.SilkS" user "B.Silkscreen")
		(1 "F.Mask" user)
		(3 "B.Mask" user)
		(17 "Dwgs.User" user "User.Drawings")
		(19 "Cmts.User" user "User.Comments")
		(21 "Eco1.User" user "User.Eco1")
		(23 "Eco2.User" user "User.Eco2")
		(25 "Edge.Cuts" user)
		(27 "Margin" user)
		(31 "F.CrtYd" user "F.Courtyard")
		(29 "B.CrtYd" user "B.Courtyard")
		(35 "F.Fab" user)
		(33 "B.Fab" user)
	)
	(footprint "antmicro-footprints:VFQFPN-40-1EP_5x5mm_P0.4mm_EP3.5x3.5mm"
		(layer "F.Cu")
		(at 215.678 128.725 -90)
		(descr "UQFN, 40 Pin")
		(tags "UQFN NoLead")
		(property "Reference" "U37"
			(at -3.015 -1.022 180)
			(layer "F.SilkS")
			(effects
				(font
					(size 0.7 0.7)
					(thickness 0.15)
				)
				(justify right bottom)
			)
		)
		(property "Value" "9DBL0651CKILF"
			(at 0 3.9 90)
			(layer "F.Fab")
			(effects
				(font
					(size 0.7 0.7)
					(thickness 0.15)
				)
				(justify right bottom)
			)
		)
		(property "Datasheet" "https://eu.mouser.com/datasheet/2/698/REN_9DBL02x2_9DBL04x2_9DBL06x1_9DBL08x1C_DST_20221-3075841.pdf"
			(at 0 0 270)
			(layer "F.Fab")
			(hide yes)
			(effects
				(font
					(size 1.27 1.27)
					(thickness 0.15)
				)
			)
		)
		(property "Author" "Antmicro"
			(at 86.953 344.403 0)
			(layer "F.Fab")
			(hide yes)
			(effects
				(font
					(size 1 1)
					(thickness 0.15)
				)
			)
		)
		(property "License" "Apache-2.0"
			(at 86.953 344.403 0)
			(layer "F.Fab")
			(hide yes)
			(effects
				(font
					(size 1 1)
					(thickness 0.15)
				)
			)
		)
		(property "MPN" "9DBL0651CKILF"
			(at 86.953 344.403 0)
			(layer "F.Fab")
			(hide yes)
			(effects
				(font
					(size 1 1)
					(thickness 0.15)
				)
			)
		)
		(property "Manufacturer" "Renesas"
			(at 86.953 344.403 0)
			(layer "F.Fab")
			(hide yes)
			(effects
				(font
					(size 1 1)
					(thickness 0.15)
				)
			)
		)
		(sheetname "PCIe misc")
		(sheetfile "pcie_misc.kicad_sch")
		(attr smd)
		(pad "33" smd roundrect
			(at 0.998 -2.476 270)
			(size 0.2 0.75)
			(layers "F.Cu" "F.Mask" "F.Paste")
			(roundrect_rratio 0.25)
			(net 619 "/PCIe misc/DIF4+")
			(pinfunction "DIF4+")
			(pintype "output")
			(teardrops
				(best_length_ratio 0.2)
				(max_length 1)
				(best_width_ratio 0.9)
				(max_width 2)
				(curved_edges yes)
				(filter_ratio 0.9)
				(enabled yes)
				(allow_two_segments yes)
				(prefer_zone_connections yes)
			)
		)
		(pad "34" smd roundrect
			(at 0.598 -2.476 270)
			(size 0.2 0.75)
			(layers "F.Cu" "F.Mask" "F.Paste")
			(roundrect_rratio 0.25)
			(net 620 "/PCIe misc/DIF4-")
			(pinfunction "DIF4-")
			(pintype "output")
			(teardrops
				(best_length_ratio 0.2)
				(max_length 1)
				(best_width_ratio 0.9)
				(max_width 2)
				(curved_edges yes)
				(filter_ratio 0.9)
				(enabled yes)
				(allow_two_segments yes)
				(prefer_zone_connections yes)
			)
		)
		(pad "35" smd roundrect
			(at 0.2 -2.476 270)
			(size 0.2 0.75)
			(layers "F.Cu" "F.Mask" "F.Paste")
			(roundrect_rratio 0.25)
			(net 606 "Net-(U37-~{OE4})")
			(pinfunction "~{OE4}")
			(pintype "input")
			(teardrops
				(best_length_ratio 0.2)
				(max_length 1)
				(best_width_ratio 0.9)
				(max_width 2)
				(curved_edges yes)
				(filter_ratio 0.9)
				(enabled yes)
				(allow_two_segments yes)
				(prefer_zone_connections yes)
			)
		)
		(pad "36" smd roundrect
			(at -0.202 -2.476 270)
			(size 0.2 0.75)
			(layers "F.Cu" "F.Mask" "F.Paste")
			(roundrect_rratio 0.25)
			(net 621 "/PCIe misc/DIF5+")
			(pinfunction "DIF5+")
			(pintype "output")
			(teardrops
				(best_length_ratio 0.2)
				(max_length 1)
				(best_width_ratio 0.9)
				(max_width 2)
				(curved_edges yes)
				(filter_ratio 0.9)
				(enabled yes)
				(allow_two_segments yes)
				(prefer_zone_connections yes)
			)
		)
		(pad "37" smd roundrect
			(at -0.6 -2.476 270)
			(size 0.2 0.75)
			(layers "F.Cu" "F.Mask" "F.Paste")
			(roundrect_rratio 0.25)
			(net 622 "/PCIe misc/DIF5-")
			(pinfunction "DIF5-")
			(pintype "output")
			(teardrops
				(best_length_ratio 0.2)
				(max_length 1)
				(best_width_ratio 0.9)
				(max_width 2)
				(curved_edges yes)
				(filter_ratio 0.9)
				(enabled yes)
				(allow_two_segments yes)
				(prefer_zone_connections yes)
			)
		)
		(pad "38" smd roundrect
			(at -1 -2.476 270)
			(size 0.2 0.75)
			(layers "F.Cu" "F.Mask" "F.Paste")
			(roundrect_rratio 0.25)
			(net 608 "Net-(U37-~{OE5})")
			(pinfunction "~{OE5}")
			(pintype "input")
			(teardrops
				(best_length_ratio 0.2)
				(max_length 1)
				(best_width_ratio 0.9)
				(max_width 2)
				(curved_edges yes)
				(filter_ratio 0.9)
				(enabled yes)
				(allow_two_segments yes)
				(prefer_zone_connections yes)
			)
		)
		(pad "39" smd roundrect
			(at -1.401 -2.476 270)
			(size 0.2 0.75)
			(layers "F.Cu" "F.Mask" "F.Paste")
			(roundrect_rratio 0.25)
			(net 2 "+3V3")
			(pinfunction "VDDIO")
			(pintype "passive")
			(teardrops
				(best_length_ratio 0.2)
				(max_length 1)
				(best_width_ratio 0.9)
				(max_width 2)
				(curved_edges yes)
				(filter_ratio 0.9)
				(enabled yes)
				(allow_two_segments yes)
				(prefer_zone_connections yes)
			)
		)
		(pad "40" smd roundrect
			(at -1.801 -2.476 270)
			(size 0.2 0.75)
			(layers "F.Cu" "F.Mask" "F.Paste")
			(roundrect_rratio 0.25)
			(net 609 "Net-(U37-~{CKPWRGD_PD})")
			(pinfunction "~{CKPWRGD_PD}")
			(pintype "input")
			(teardrops
				(best_length_ratio 0.2)
				(max_length 1)
				(best_width_ratio 0.9)
				(max_width 2)
				(curved_edges yes)
				(filter_ratio 0.9)
				(enabled yes)
				(allow_two_segments yes)
				(prefer_zone_connections yes)
			)
		)
		(pad "41" smd rect
			(at 0 0 270)
			(size 3.5 3.5)
			(layers "F.Cu" "F.Mask")
			(net 1 "GND")
			(pinfunction "EPAD")
			(pintype "passive")
			(teardrops
				(best_length_ratio 0.2)
				(max_length 1)
				(best_width_ratio 0.9)
				(max_width 2)
				(curved_edges yes)
				(filter_ratio 0.9)
				(enabled no)
				(allow_two_segments yes)
				(prefer_zone_connections yes)
			)
		)
	)
)
